# TIMECARD (Time Appliance Project (Time Card)) — schematic netlist excerpt (pin names and nets, part order shuffled) for the footprints in the layout excerpt that follows; sources: Cadence DE-HDL packaged netlist, KiCad conversion of R4006-B0001-02_R01.brd

TP44  TP_PIONT  pkg TP010CT020B030_PTH  page 25 : \1\ = FPGA_DONE
TP56  TP_PIONT  pkg TP010CT020B030_PTH  page 25 : \1\ = XP1R8V_FPGA
C262  CAPACITOR  0.1UF 25V 10%  pkg SMC_0402R_H022  page 29 : \1\ = VIN_XP1R0V ; \2\ = SG
SP25  SOLDER_PREFORM  pkg 0201_SOLDER_PREFORM_4MIL  page 34 : \1\ = NC ; \2\ = NC

(kicad_pcb
	(version 20260206)
	(generator "pcbnew")
	(generator_version "10.0")
	(general
		(thickness 1.6)
		(legacy_teardrops no)
	)
	(paper "A4")
	(title_block
		(title "timecard-production-celestica-r4006 — R4006-B0001-02_R01.brd")
		(comment 1 "Time Appliance Project (Time Card) / footprints 8-11 of 1113")
	)
	(layers
		(0 "F.Cu" signal "TOP")
		(4 "In1.Cu" signal "L02_GND1")
		(6 "In2.Cu" signal "L03_SIG1")
		(8 "In3.Cu" signal "L04_GND2")
		(10 "In4.Cu" signal "L05_VCC1")
		(12 "In5.Cu" signal "L06_VCC2")
		(14 "In6.Cu" signal "L07_GND3")
		(16 "In7.Cu" signal "L08_SIG2")
		(18 "In8.Cu" signal "L09_GND4")
		(2 "B.Cu" signal "BOTTOM")
		(9 "F.Adhes" user "F.Adhesive")
		(11 "B.Adhes" user "B.Adhesive")
		(13 "F.Paste" user "Package Geometry/Pastemask Top")
		(15 "B.Paste" user "Package Geometry/Pastemask Bottom")
		(5 "F.SilkS" user "Ref Des/Silkscreen Top")
		(7 "B.SilkS" user "Ref Des/Silkscreen Bottom")
		(1 "F.Mask" user "Board Geometry/Soldermask Top")
		(3 "B.Mask" user "Board Geometry/Soldermask Bottom")
		(17 "Dwgs.User" user "User.Drawings")
		(19 "Cmts.User" user "User.Comments")
		(21 "Eco1.User" user "User.Eco1")
		(23 "Eco2.User" user "User.Eco2")
		(25 "Edge.Cuts" user "Board Geometry/Outline")
		(27 "Margin" user)
		(31 "F.CrtYd" user "Package Geometry/Place Bound Top")
		(29 "B.CrtYd" user "Package Geometry/Place Bound Bottom")
		(35 "F.Fab" user "Ref Des/Assembly Top")
		(33 "B.Fab" user "Ref Des/Assembly Bottom")
	)
	(footprint ""
		(layer "F.Cu")
		(at 135.763 -64.4144 180)
		(property "Reference" "TP56"
			(at -1.30175 -0.3048 90)
			(unlocked yes)
			(layer "F.SilkS")
			(effects
				(font
					(size 0.635 0.4064)
					(thickness 0.1524)
				)
				(justify left)
			)
		)
		(property "Value" ""
			(at 0 0 180)
			(layer "F.Fab")
			(effects
				(font
					(size 1.27 1.27)
				)
			)
		)
		(property "Device Type" "TP_PIONT-TP010CT020B030_PTH-TPA"
			(at -1.341882 0.996696 180)
			(unlocked yes)
			(layer "F.Fab")
			(hide yes)
			(effects
				(font
					(size 0.7874 0.5842)
					(thickness 0.1524)
				)
				(justify left)
			)
		)
		(duplicate_pad_numbers_are_jumpers no)
		(fp_poly
			(pts
				(arc
					(start -0.889 0)
					(mid 0.889 0)
					(end -0.889 0)
				)
			)
			(stroke
				(width 0)
				(type default)
			)
			(fill no)
			(layer "B.CrtYd")
		)
		(fp_poly
			(pts
				(arc
					(start -0.889 0)
					(mid 0.889 0)
					(end -0.889 0)
				)
			)
			(stroke
				(width 0)
				(type default)
			)
			(fill no)
			(layer "F.CrtYd")
		)
		(pad "1" thru_hole circle
			(at 0 0 180)
			(size 0.508 0.508)
			(drill 0.254)
			(layers "*.Cu" "*.Mask")
			(remove_unused_layers no)
			(net "XP1R8V_FPGA")
			(clearance 0.1016)
			(padstack
				(mode front_inner_back)
				(layer "Inner"
					(shape circle)
					(size 0.508 0.508)
					(clearance 0.1016)
				)
				(layer "B.Cu"
					(shape circle)
					(size 0.762 0.762)
					(clearance -0.0254)
				)
			)
		)
	)
	(footprint ""
		(layer "F.Cu")
		(at 134.62 -103.251)
		(property "Reference" "TP44"
			(at -3.8862 0.29337 0)
			(unlocked yes)
			(layer "F.SilkS")
			(effects
				(font
					(size 0.7874 0.5842)
					(thickness 0.1524)
				)
				(justify left)
			)
		)
		(property "Value" ""
			(at 0 0 0)
			(layer "F.Fab")
			(effects
				(font
					(size 1.27 1.27)
				)
			)
		)
		(property "Device Type" "TP_PIONT-TP010CT020B030_PTH-TPA"
			(at -1.341882 0.996696 0)
			(unlocked yes)
			(layer "F.Fab")
			(hide yes)
			(effects
				(font
					(size 0.7874 0.5842)
					(thickness 0.000001)
				)
				(justify left)
			)
		)
		(duplicate_pad_numbers_are_jumpers no)
		(fp_poly
			(pts
				(arc
					(start 0.889 0)
					(mid -0.889 0)
					(end 0.889 0)
				)
			)
			(stroke
				(width 0)
				(type default)
			)
			(fill no)
			(layer "B.CrtYd")
		)
		(fp_poly
			(pts
				(arc
					(start 0.889 0)
					(mid -0.889 0)
					(end 0.889 0)
				)
			)
			(stroke
				(width 0)
				(type default)
			)
			(fill no)
			(layer "F.CrtYd")
		)
		(pad "1" thru_hole circle
			(at 0 0)
			(size 0.508 0.508)
			(drill 0.254)
			(layers "*.Cu" "*.Mask")
			(remove_unused_layers no)
			(net "FPGA_DONE")
			(clearance 0.1016)
			(padstack
				(mode front_inner_back)
				(layer "Inner"
					(shape circle)
					(size 0.508 0.508)
					(clearance 0.1016)
				)
				(layer "B.Cu"
					(shape circle)
					(size 0.762 0.762)
					(clearance -0.0254)
				)
			)
		)
	)
	(footprint ""
		(layer "F.Cu")
		(at 48.26 -126.238)
		(property "Reference" "SP25"
			(at 0 0 0)
			(layer "F.SilkS")
			(hide yes)
			(effects
				(font
					(size 1.27 1.27)
				)
			)
		)
		(property "Value" ""
			(at 0 0 0)
			(layer "F.Fab")
			(effects
				(font
					(size 1.27 1.27)
				)
			)
		)
		(duplicate_pad_numbers_are_jumpers no)
	)
	(footprint ""
		(layer "F.Cu")
		(at 144.78 -54.102 -90)
		(property "Reference" "C262"
			(at 1.524 -3.08737 90)
			(unlocked yes)
			(layer "F.SilkS")
			(effects
				(font
					(size 0.7874 0.5842)
					(thickness 0.1524)
				)
			)
		)
		(property "Value" "VAL*"
			(at 0.0762 2.067306 270)
			(unlocked yes)
			(layer "F.Fab")
			(hide yes)
			(effects
				(font
					(size 0.7874 0.5842)
					(thickness 0.1524)
				)
			)
		)
		(property "Device Type" "CAPACITOR-G105-0B104-EK,0.1UF,A"
			(at 0.0508 1.127506 270)
			(unlocked yes)
			(layer "F.Fab")
			(hide yes)
			(effects
				(font
					(size 0.7874 0.5842)
					(thickness 0.1524)
				)
			)
		)
		(property "User Part Number" "PARTNUM*"
			(at 0.1016 4.023106 270)
			(unlocked yes)
			(layer "Cmts.User")
			(hide yes)
			(effects
				(font
					(size 0.7874 0.5842)
					(thickness 0.1524)
				)
			)
		)
		(property "Tolerance" "TOL*"
			(at 0.0762 3.032506 270)
			(unlocked yes)
			(layer "Cmts.User")
			(hide yes)
			(effects
				(font
					(size 0.7874 0.5842)
					(thickness 0.1524)
				)
			)
		)
		(duplicate_pad_numbers_are_jumpers no)
		(fp_line
			(start -1.143 0.5588)
			(end 1.143 0.5588)
			(stroke
				(width 0.1)
				(type default)
			)
			(layer "F.SilkS")
		)
		(fp_line
			(start 1.143 0.5588)
			(end 1.143 -0.5588)
			(stroke
				(width 0.1)
				(type default)
			)
			(layer "F.SilkS")
		)
		(fp_line
			(start -1.143 -0.5588)
			(end -1.143 0.5588)
			(stroke
				(width 0.1)
				(type default)
			)
			(layer "F.SilkS")
		)
		(fp_line
			(start 1.143 -0.5588)
			(end -1.143 -0.5588)
			(stroke
				(width 0.1)
				(type default)
			)
			(layer "F.SilkS")
		)
		(fp_rect
			(start 1.143 0.5588)
			(end -1.143 -0.5588)
			(stroke
				(width 0)
				(type default)
			)
			(fill no)
			(layer "F.CrtYd")
		)
		(fp_line
			(start -0.508 0.3048)
			(end 0.508 0.3048)
			(stroke
				(width 0.1)
				(type default)
			)
			(layer "F.Fab")
		)
		(fp_line
			(start 0.508 0.3048)
			(end 0.508 -0.3048)
			(stroke
				(width 0.1)
				(type default)
			)
			(layer "F.Fab")
		)
		(fp_line
			(start -0.508 -0.3048)
			(end -0.508 0.3048)
			(stroke
				(width 0.1)
				(type default)
			)
			(layer "F.Fab")
		)
		(fp_line
			(start 0.508 -0.3048)
			(end -0.508 -0.3048)
			(stroke
				(width 0.1)
				(type default)
			)
			(layer "F.Fab")
		)
		(pad "1" smd rect
			(at -0.5334 0 270)
			(size 0.7112 0.6096)
			(layers "F.Cu" "F.Mask" "F.Paste")
			(net "VIN_XP1R0V")
		)
		(pad "2" smd rect
			(at 0.5334 0 270)
			(size 0.7112 0.6096)
			(layers "F.Cu" "F.Mask" "F.Paste")
			(net "SG")
		)
		(zone
			(layer "F.Cu")
			(hatch none 0.5)
			(connect_pads
				(clearance 0)
			)
			(min_thickness 0.25)
			(keepout
				(tracks allowed)
				(vias not_allowed)
				(pads allowed)
				(copperpour not_allowed)
				(footprints allowed)
			)
			(placement
				(enabled no)
				(sheetname "")
			)
			(fill
				(thermal_gap 0.5)
				(thermal_bridge_width 0.5)
				(island_removal_mode 0)
			)
			(polygon
				(pts
					(xy 144.4752 -54.0258) (xy 145.0848 -54.0258) (xy 145.0848 -54.1782) (xy 144.4752 -54.1782)
				)
			)
		)
	)
)
